# S9S_MB_2U (Grand Teton) — schematic parts with pin connectivity, parts 2953–3091 of 6093; source: Cadence DE-HDL packaged netlist (pstxprt.dat, pstxnet.dat, pstchip.dat)

PR3852  Q_RES  71.5K 1% EMPTY  pkg 0402LF  page 163 : 1 = P12V_OCP_V3_2 ; 2 = P12V_OCP_OV_FB_2
PR3853  Q_RES  120K 1% CHIP  pkg 0402LF  page 163 : 1 = P12V_AUX ; 2 = P12V_OCP_OV_FB_2
PR3854  Q_RES  10K 1% CHIP  pkg 0402LF  page 163 : 1 = P12V_OCP_OV_FB_2 ; 2 = GND
PR3855  Q_RES  71.5K 1% EMPTY  pkg 0402LF  page 163 : 1 = P3V3_OCP_MODE_2 ; 2 = GND
PR3856  Q_RES  1.33K 1% EMPTY  pkg 0402LF  page 163 : 1 = GND ; 2 = P3V3_OCP_ILIMIT_2
PR3857  Q_RES  49.9 1% CHIP  pkg 0603LF  page 163 : 1 = P12V_AUX ; 2 = P12V_OCP_AVIN_PD_2
PR3910  Q_RES  0 5% CHIP  pkg 0402LF  page 302 : 1 = HSC_VDD_R_1 ; 2 = HSC_VDD
PR3911  Q_RES  0 5% CHIP  pkg 0402LF  page 302 : 1 = HSC_VDD_R_2 ; 2 = HSC_VDD
PR3912  Q_RES  120K 1% CHIP  pkg 0402LF  page 302 : 1 = AGND_HSC ; 2 = HSC_MODE_2
PR3914  Q_RES  2K 0.1% CHIP  pkg 0402LF  page 302 : 1 = HSC_CS_1 ; 2 = AGND_HSC
PR3915  Q_RES  2K 0.1% CHIP  pkg 0402LF  page 302 : 1 = HSC_CS_2 ; 2 = AGND_HSC
PR3916  Q_RES  0 5% CHIP  pkg 0402LF  page 302 : 1 = HSC_SCREF ; 2 = HSC_SCREF_1
PR3917  Q_RES  0 5% CHIP  pkg 0402LF  page 302 : 1 = HSC_SCREF ; 2 = HSC_SCREF_2
PR3918  Q_RES  2K 0.1% CHIP  pkg 0402LF  page 302 : 1 = HSC_IMON ; 2 = AGND_HSC
PR3919  Q_RES  0 5% CHIP  pkg 0402LF  page 302 : 1 = HSC_D_OC_1 ; 2 = HSC_D_OC_R
PR3920  Q_RES  0 5% CHIP  pkg 0402LF  page 302 : 1 = HSC_FLT_TYPE_1 ; 2 = HSC_FLT_TYPE
PR3921  Q_RES  0 5% CHIP  pkg 0402LF  page 302 : 1 = HSC_D_OC_2 ; 2 = HSC_D_OC_R
PR3922  Q_RES  0 5% CHIP  pkg 0402LF  page 302 : 1 = HSC_FLT_TYPE_2 ; 2 = HSC_FLT_TYPE
PR3926  Q_RES  75K 0.1% CHIP  pkg 0402LF  page 301 : 1 = P12V_PSU ; 2 = HSC_VSENSE
PR3927  Q_RES  4.99K 0.1% CHIP  pkg 0402LF  page 301 : 1 = HSC_VSENSE ; 2 = AGND_HSC
PR3928  Q_RES  0 5% CHIP  pkg 0402LF  page 301 : 1 = HSC_ON ; 2 = HSC_ON_R
PR3929  Q_RES  1K 1% EMPTY  pkg 0402LF  page 301 : 1 = HSC_ADDR ; 2 = HSC_VDD18
PR3930  Q_RES  0 5% CHIP  pkg 0402LF  page 301 : 1 = AGND_HSC ; 2 = HSC_ADDR
PR3931  Q_RES  75K 0.1% CHIP  pkg 0402LF  page 301 : 1 = P12V_AUX ; 2 = HSC_VOSEN
PR3932  Q_RES  4.99K 0.1% CHIP  pkg 0402LF  page 301 : 1 = HSC_VOSEN ; 2 = AGND_HSC
PR3935  Q_RES  10K 1% CHIP  pkg 0402LF  page 301 : 1 = HSC_VTEMP ; 2 = AGND_HSC
PR3937  Q_RES  120K 1% CHIP  pkg 0402LF  page 301 : 1 = HSC_MODE ; 2 = AGND_HSC
PR3944  Q_RES  46.4K 1% CHIP  pkg 0402LF  page 193 : 1 = P12V_E1S_ISET_0 ; 2 = GND
PR3945  Q_RES  71.5K 1% EMPTY  pkg 0402LF  page 193 : 1 = P3V3_E1S_MODE_0 ; 2 = GND
PR3947  Q_RES  2.8K 1% EMPTY  pkg 0402LF  page 193 : 1 = GND ; 2 = P3V3_E1S_ILIMIT_0
PR3949  Q_RES  56K 1% CHIP  pkg 0402LF  page 193 : 1 = P12V_E1S_IMON_0 ; 2 = GND
PR3950  Q_RES  100 1% EMPTY  pkg 0402LF  page 193 : 1 = P12V_E1S_0 ; 2 = P12V_E1S_AVIN_PD_0
PR3951  Q_RES  10K 1% CHIP  pkg 0402LF  page 193 : 1 = P12V_E1S_FLTB_0 ; 2 = P3V3_AUX
PR3952  Q_RES  71.5K 1% EMPTY  pkg 0402LF  page 193 : 1 = P12V_E1S_0 ; 2 = P12V_E1S_OV_FB_0
PR3953  Q_RES  120K 1% CHIP  pkg 0402LF  page 193 : 1 = P12V_AUX ; 2 = P12V_E1S_OV_FB_0
PR3954  Q_RES  10K 1% CHIP  pkg 0402LF  page 193 : 1 = P12V_E1S_OV_FB_0 ; 2 = GND
PR3957  Q_RES  49.9 1% CHIP  pkg 0603LF  page 193 : 1 = P12V_AUX ; 2 = P12V_E1S_AVIN_PD_0
PR3960  Q_RES  160K 1% EMPTY  pkg 0402LF  page 192 : 1 = P12V_AUX ; 2 = P12V_E1S_UV_0
PR3961  Q_RES  6.8K 1% EMPTY  pkg 0402LF  page 192 : 1 = P12V_E1S_UV_0 ; 2 = P12V_E1S_OV_0
PR3962  Q_RES  15K 1% EMPTY  pkg 0402LF  page 192 : 1 = P12V_E1S_OV_0 ; 2 = GND
PR3963  Q_RES  25.5K 1% CHIP  pkg 0402LF  page 192 : 1 = P3V3_AUX ; 2 = P3V3_E1S_UV_0
PR3964  Q_RES  7.15K 1% CHIP  pkg 0402LF  page 192 : 1 = P3V3_E1S_UV_0 ; 2 = P3V3_E1S_OV_0
PR3965  Q_RES  15K 1% CHIP  pkg 0402LF  page 192 : 1 = P3V3_E1S_OV_0 ; 2 = GND
PR3966  Q_RES  10 1% EMPTY  pkg 0402LF  page 192 : 1 = P12V_AUX ; 2 = P12V_E1S_VCC_0
PR3967  Q_RES  10 1% CHIP  pkg 0402LF  page 192 : 1 = P3V3_AUX ; 2 = P3V3_E1S_VCC_0
PR3968  Q_RES  9.31K 1% EMPTY  pkg 0402LF  page 192 : 1 = P12V_E1S_CB_0 ; 2 = GND
PR3969  Q_RES  2.49K 1% CHIP  pkg 0402LF  page 192 : 1 = P3V3_E1S_CB_0 ; 2 = GND
PR3970  Q_RES  2.67K 1% EMPTY  pkg 0402LF  page 192 : 1 = P12V_E1S_SENSE_0 ; 2 = GND
PR3971  Q_RES  9.76K 1% CHIP  pkg 0402LF  page 192 : 1 = P3V3_E1S_SENSE_0 ; 2 = GND
PR3980  Q_RES  0 5% CHIP  pkg 0402LF  page 303 : 1 = HSC_VDD_R_3 ; 2 = HSC_VDD
PR3981  Q_RES  0 5% CHIP  pkg 0402LF  page 303 : 1 = HSC_VDD_R_4 ; 2 = HSC_VDD
PR3982  Q_RES  120K 1% CHIP  pkg 0402LF  page 303 : 1 = AGND_HSC ; 2 = HSC_MODE_3
PR3984  Q_RES  120K 1% CHIP  pkg 0402LF  page 303 : 1 = AGND_HSC ; 2 = HSC_MODE_4
PR3986  Q_RES  2K 0.1% CHIP  pkg 0402LF  page 303 : 1 = HSC_CS_3 ; 2 = AGND_HSC
PR3987  Q_RES  2K 0.1% CHIP  pkg 0402LF  page 303 : 1 = HSC_CS_4 ; 2 = AGND_HSC
PR3988  Q_RES  0 5% CHIP  pkg 0402LF  page 303 : 1 = HSC_SCREF ; 2 = HSC_SCREF_3
PR3989  Q_RES  0 5% CHIP  pkg 0402LF  page 303 : 1 = HSC_SCREF ; 2 = HSC_SCREF_4
PR3990  Q_RES  2K 0.1% CHIP  pkg 0402LF  page 303 : 1 = HSC_IMON ; 2 = AGND_HSC
PR3991  Q_RES  2K 0.1% CHIP  pkg 0402LF  page 303 : 1 = HSC_IMON ; 2 = AGND_HSC
PR3992  Q_RES  0 5% CHIP  pkg 0402LF  page 303 : 1 = HSC_D_OC_3 ; 2 = HSC_D_OC_R
PR3993  Q_RES  0 5% CHIP  pkg 0402LF  page 303 : 1 = HSC_FLT_TYPE_3 ; 2 = HSC_FLT_TYPE
PR3994  Q_RES  0 5% CHIP  pkg 0402LF  page 303 : 1 = HSC_D_OC_4 ; 2 = HSC_D_OC_R
PR3995  Q_RES  0 5% CHIP  pkg 0402LF  page 303 : 1 = HSC_FLT_TYPE_4 ; 2 = HSC_FLT_TYPE
PR3999  Q_RES  24.3K 1% CHIP  pkg 0402LF  page 242 : 1 = P12V_SCM_ISET ; 2 = GND
PR4000  Q_RES  160K 1% EMPTY  pkg 0402LF  page 242 : 1 = P12V_AUX ; 2 = P12V_SCM_UV
PR4001  Q_RES  6.8K 1% EMPTY  pkg 0402LF  page 242 : 1 = P12V_SCM_UV ; 2 = P12V_SCM_OV
PR4002  Q_RES  15K 1% EMPTY  pkg 0402LF  page 242 : 1 = P12V_SCM_OV ; 2 = GND
PR4003  Q_RES  10 1% EMPTY  pkg 0402LF  page 242 : 1 = P12V_AUX ; 2 = P12V_SCM_VCC
PR4004  Q_RES  17.8K 1% EMPTY  pkg 0402LF  page 242 : 1 = P12V_SCM_CB ; 2 = GND
PR4005  Q_RES  30.1K 1% CHIP  pkg 0402LF  page 242 : 1 = P12V_SCM_IMON ; 2 = GND
PR4006  Q_RES  100 1% EMPTY  pkg 0402LF  page 242 : 1 = P12V_SCM_R ; 2 = P12V_SCM_AVIN_PD
PR4007  Q_RES  10K 1% CHIP  pkg 0402LF  page 242 : 1 = P12V_SCM_FLTB_N ; 2 = P3V3_AUX
PR4008  Q_RES  1.33K 1% EMPTY  pkg 0402LF  page 242 : 1 = P12V_SCM_SENSE ; 2 = GND
PR4009  Q_RES  71.5K 1% EMPTY  pkg 0402LF  page 242 : 1 = P12V_SCM_R ; 2 = P12V_SCM_OV_FB
PR4010  Q_RES  120K 1% CHIP  pkg 0402LF  page 242 : 1 = P12V_AUX ; 2 = P12V_SCM_OV_FB
PR4011  Q_RES  10K 1% CHIP  pkg 0402LF  page 242 : 1 = P12V_SCM_OV_FB ; 2 = GND
PR4012  Q_RES  0 5% EMPTY  pkg 0402LF  page 242 : 1 = P12V_SCM_PWRGD ; 2 = HP_LVC3_SCM_HSC_PWRGD
PR4014  Q_RES  49.9 1% CHIP  pkg 0603LF  page 242 : 1 = P12V_AUX ; 2 = P12V_SCM_AVIN_PD
PR4217  Q_RES  0 5% EMPTY  pkg 0402LF  page 266 : 1 = PVCCFA_EHV_FIVRA_CPU0_IMON4 ; 2 = GND
PR4218  Q_RES  0 5% EMPTY  pkg 0402LF  page 266 : 1 = PVCCFA_EHV_FIVRA_CPU0_IMON3 ; 2 = GND
PR4219  Q_RES  499 1% CHIP  pkg 0402LF  page 267 : 1 = PVCCIN_CPU0 ; 2 = GND
PR4220  Q_RES  0 5% CHIP  pkg 0402LF  page 274 : 1 = PVCCINFAON_CPU0_CSPIN ; 2 = GND
PR4221  Q_RES  0 5% CHIP  pkg 0402LF  page 274 : 1 = NC_PVCCINFAON_CPU0_ACSP3 ; 2 = GND
PR4222  Q_RES  0 5% CHIP  pkg 0402LF  page 274 : 1 = NC_PVCCINFAON_CPU0_ACSP4 ; 2 = GND
PR4223  Q_RES  0 5% CHIP  pkg 0402LF  page 274 : 1 = NC_PVCCINFAON_CPU0_ACSP5 ; 2 = GND
PR4224  Q_RES  0 5% CHIP  pkg 0402LF  page 274 : 1 = NC_PVCCINFAON_CPU0_ACSP6 ; 2 = GND
PR4225  Q_RES  0 5% CHIP  pkg 0402LF  page 274 : 1 = NC_PVCCINFAON_CPU0_ACSP7 ; 2 = GND
PR4226  Q_RES  499 1% CHIP  pkg 0402LF  page 275 : 1 = PVCCINFAON_CPU0 ; 2 = GND
PR4227  Q_RES  0 5% EMPTY  pkg 0402LF  page 276 : 1 = PVCCFA_EHV_CPU0_VDD1 ; 2 = PVCCFA_EHV_CPU0_NC2
PR4228  Q_RES  0 5% EMPTY  pkg 0402LF  page 276 : 1 = PVCCFA_EHV_CPU0_FAULT ; 2 = GND
PR4229  Q_RES  499 1% CHIP  pkg 0402LF  page 276 : 1 = PVCCFA_EHV_CPU0 ; 2 = GND
PR4230  Q_RES  0 5% CHIP  pkg 0402LF  page 278 : 1 = NC_PVCCD_HV_CPU0_ACSP2 ; 2 = GND
PR4231  Q_RES  0 5% CHIP  pkg 0402LF  page 278 : 1 = NC_PVCCD_HV_CPU0_ACSP3 ; 2 = GND
PR4232  Q_RES  0 5% CHIP  pkg 0402LF  page 278 : 1 = NC_PVCCD_HV_CPU0_ACSP4 ; 2 = GND
PR4233  Q_RES  0 5% CHIP  pkg 0402LF  page 278 : 1 = NC_PVCCD_HV_CPU0_ACSP5 ; 2 = GND
PR4234  Q_RES  0 5% CHIP  pkg 0402LF  page 278 : 1 = NC_PVCCD_HV_CPU0_ACSP6 ; 2 = GND
PR4235  Q_RES  0 5% CHIP  pkg 0402LF  page 278 : 1 = NC_PVCCD_HV_CPU0_ACSP7 ; 2 = GND
PR4236  Q_RES  0 5% CHIP  pkg 0402LF  page 278 : 1 = NC_PVCCD_HV_CPU0_ACSP8 ; 2 = GND
PR4237  Q_RES  499 1% CHIP  pkg 0402LF  page 279 : 1 = PVCCD_HV_CPU0 ; 2 = GND
PR4238  Q_RES  0 5% EMPTY  pkg 0402LF  page 284 : 1 = PVCCFA_EHV_FIVRA_CPU1_IMON4 ; 2 = GND
PR4239  Q_RES  0 5% EMPTY  pkg 0402LF  page 284 : 1 = PVCCFA_EHV_FIVRA_CPU1_IMON3 ; 2 = GND
PR4240  Q_RES  499 1% CHIP  pkg 0402LF  page 285 : 1 = PVCCIN_CPU1 ; 2 = GND
PR4241  Q_RES  499 1% CHIP  pkg 0402LF  page 289 : 1 = PVCCFA_EHV_FIVRA_CPU1 ; 2 = GND
PR4242  Q_RES  0 5% CHIP  pkg 0402LF  page 292 : 1 = NC_PVCCINFAON_CPU1_ACSP3 ; 2 = GND
PR4243  Q_RES  0 5% CHIP  pkg 0402LF  page 292 : 1 = NC_PVCCINFAON_CPU1_ACSP4 ; 2 = GND
PR4244  Q_RES  0 5% CHIP  pkg 0402LF  page 292 : 1 = NC_PVCCINFAON_CPU1_ACSP5 ; 2 = GND
PR4245  Q_RES  0 5% CHIP  pkg 0402LF  page 292 : 1 = NC_PVCCINFAON_CPU1_ACSP6 ; 2 = GND
PR4246  Q_RES  0 5% CHIP  pkg 0402LF  page 292 : 1 = NC_PVCCINFAON_CPU1_ACSP7 ; 2 = GND
PR4247  Q_RES  499 1% CHIP  pkg 0402LF  page 293 : 1 = PVCCINFAON_CPU1 ; 2 = GND
PR4248  Q_RES  0 5% EMPTY  pkg 0402LF  page 294 : 1 = PVCCFA_EHV_CPU1_NC2 ; 2 = PVCCFA_EHV_CPU1_VDD1
PR4249  Q_RES  0 5% EMPTY  pkg 0402LF  page 294 : 1 = PVCCFA_EHV_CPU1_FAULT ; 2 = GND
PR4250  Q_RES  499 1% CHIP  pkg 0402LF  page 294 : 1 = PVCCFA_EHV_CPU1 ; 2 = GND
PR4251  Q_RES  0 5% CHIP  pkg 0402LF  page 296 : 1 = NC_PVCCD_HV_CPU1_ACSP2 ; 2 = GND
PR4252  Q_RES  0 5% CHIP  pkg 0402LF  page 296 : 1 = NC_PVCCD_HV_CPU1_ACSP3 ; 2 = GND
PR4253  Q_RES  0 5% CHIP  pkg 0402LF  page 296 : 1 = NC_PVCCD_HV_CPU1_ACSP4 ; 2 = GND
PR4254  Q_RES  0 5% CHIP  pkg 0402LF  page 296 : 1 = NC_PVCCD_HV_CPU1_ACSP5 ; 2 = GND
PR4255  Q_RES  0 5% CHIP  pkg 0402LF  page 296 : 1 = NC_PVCCD_HV_CPU1_ACSP6 ; 2 = GND
PR4256  Q_RES  0 5% CHIP  pkg 0402LF  page 296 : 1 = NC_PVCCD_HV_CPU1_ACSP7 ; 2 = GND
PR4257  Q_RES  0 5% CHIP  pkg 0402LF  page 296 : 1 = NC_PVCCD_HV_CPU1_ACSP8 ; 2 = GND
PR4258  Q_RES  499 1% CHIP  pkg 0402LF  page 297 : 1 = PVCCD_HV_CPU1 ; 2 = GND
PR4265  Q_RES  499 1% CHIP  pkg 0402LF  page 271 : 1 = PVCCFA_EHV_FIVRA_CPU0 ; 2 = GND
PR4271  Q_RES  0 5% CHIP  pkg 0402LF  page 282 : 1 = SW_PVNN_MAIN_CPU0_BST ; 2 = SW_PVNN_MAIN_CPU0_BST_R
PR4272  Q_RES  0 5% CHIP  pkg 0402LF  page 300 : 1 = SW_PVNN_MAIN_CPU1_BST ; 2 = SW_PVNN_MAIN_CPU1_BST_R
PR4522  Q_RES  10M 1% EMPTY  pkg 0402LF  page 162 : 1 = P12V_OCP_V3_2 ; 2 = P12V_OCP_GATE_2
PR4523  Q_RES  10M 1% CHIP  pkg 0402LF  page 162 : 1 = P3V3_OCP_V3_2_R ; 2 = P3V3_OCP_GATE_2
PR4524  Q_RES  10M 1% EMPTY  pkg 0402LF  page 156 : 1 = P12V_OCP_SFF ; 2 = P12V_OCP_GATE_1
PR4525  Q_RES  10M 1% CHIP  pkg 0402LF  page 156 : 1 = P3V3_OCP_SFF_R ; 2 = P3V3_OCP_GATE_PU202_1
PR4526  Q_RES  10M 1% EMPTY  pkg 0402LF  page 242 : 1 = P12V_SCM_R ; 2 = P12V_SCM_GATE
PR4527  Q_RES  10M 1% CHIP  pkg 0402LF  page 192 : 1 = P3V3_E1S_0_R ; 2 = P3V3_E1S_GATE_0
PR4528  Q_RES  10M 1% EMPTY  pkg 0402LF  page 192 : 1 = P12V_E1S_0 ; 2 = P12V_E1S_GATE_0
PR4540  Q_RES  20K 1% CHIP  pkg 0402LF  page 242 : 1 = P12V_SCM_ISET ; 2 = P12V_SCM_ISET_R
PR4541  Q_RES  20K 1% CHIP  pkg 0402LF  page 193 : 1 = P12V_E1S_ISET_0 ; 2 = P12V_E1S_ISET_0_R
PR4683  Q_RES  0 5% CHIP  pkg 0402LF  page 282 : 1 = PVNN_MAIN_CPU0_FB_RC ; 2 = PVNN_MAIN_CPU0
PR4698  Q_RES  0 5% EMPTY  pkg 0402LF  page 282 : 1 = PVNN_MAIN_CPU0_FB_RC ; 2 = PVNN_MAIN_CPU0
PR4699  Q_RES  0 5% CHIP  pkg 0402LF  page 300 : 1 = PVNN_MAIN_CPU1_FB_RC ; 2 = PVNN_MAIN_CPU1
PR4700  Q_RES  0 5% EMPTY  pkg 0402LF  page 300 : 1 = PVNN_MAIN_CPU1_FB_RC ; 2 = PVNN_MAIN_CPU1
PR5481  Q_RES  4.53K 1% CHIP  pkg 0402LF  page 156 : 1 = P3V3_OCP_SENSE_1 ; 2 = GND
PR5484  Q_RES  30.1K 1% EMPTY  pkg 0402LF  page 156 : 1 = P12V_OCP_CB_1 ; 2 = GND

PU5  ISL69260IRAZT  ISL69260IRAZ-T IC  pkg QFN40_TH_0-4_5X5XE  page 274
  1  PWM0  OUT  = PVCCFA_EHV_CPU0_BPWM1
  2  PWM1  OUT  = NC_PVCCINFAON_CPU0_APWM7
  3  PWM2  OUT  = NC_PVCCINFAON_CPU0_APWM6
  4  PWM3  OUT  = NC_PVCCINFAON_CPU0_APWM5
  5  PWM4  OUT  = NC_PVCCINFAON_CPU0_APWM4
  6  PWM5  OUT  = NC_PVCCINFAON_CPU0_APWM3
  7  PWM6  OUT  = PVCCINFAON_CPU0_APWM2
  8  PWM7  OUT  = PVCCINFAON_CPU0_APWM1
  9  PMSDA  BI  = SMB_DIO_PVCCINFAON_CPU0
  10  PMSCL  IN  = SMB_CLK_PVCCINFAON_CPU0
  11  \npmalert#\  OUT  = NC_PVCCINFAON_CPU0_SMB_ALERT
  12  PG0  OUT  = PWRGD_PVCCINFAON_CPU0_R
  13  EN0  IN  = PVCCINFAON_CPU0_EN_R
  14  \nvrhot#\  OUT  = IRQ_PVCCFA_CPU0_VRHOT_N
  15  \npinalert#||npsyscrit#\  OUT  = PVCCINFAON_CPU0_PIN_ALERT
  16  PG1  OUT  = PWRGD_PVCCFA_EHV_CPU0_R
  17  SVCLK  IN  = SVID_CLK_PVCCINFAON_CPU0_R
  18  SVDATA  BI  = SVID_DIO_PVCCINFAON_CPU0_R
  19  \nsvalert#\  OUT  = SVID_ALERT_PVCCINFAON_CPU0_R
  20  EN1  IN  = PVCCFA_EHV_CPU0_EN_R
  21  VSEN0  IN  = SH_PVCCINFAON_CPU0_R
  22  RGND0  IN  = VSENSE_PVCCINFAON_CPU0_DN
  23  CS7  IN  = PVCCINFAON_CPU0_ACSP1
  24  CS6  IN  = PVCCINFAON_CPU0_ACSP2
  25  CS5  IN  = NC_PVCCINFAON_CPU0_ACSP3
  26  CS4  IN  = NC_PVCCINFAON_CPU0_ACSP4
  27  CS3  IN  = NC_PVCCINFAON_CPU0_ACSP5
  28  CS2  IN  = NC_PVCCINFAON_CPU0_ACSP6
  29  CS1  IN  = NC_PVCCINFAON_CPU0_ACSP7
  30  CS0  IN  = PVCCFA_EHV_CPU0_BCSP1
  31  RGND1  IN  = VSENSE_PVCCFA_EHV_CPU0_DN
  32  VSEN1  IN  = SH_PVCCFA_EHV_CPU0_R
  33  CFP  OUT  = PVCCINFAON_CPU0_VR_FAULT
  34  ADDR_CFG  IN  = PVCCINFAON_CPU0_ADDR
  35  TEMP0  IN  = PVCCINFAON_CPU0_ATSEN
  36  \temp1||isys\  IN  = PVCCFA_EHV_CPU0_BTSEN
  37  \vmon||iinsen||vsys||isys\  IN  = PVCCINFAON_CPU0_CSPIN
  38  \vinsen||vsys\  IN  = PVCCINFAON_CPU0_VIN_CSNIN
  39  VCC  POWER  = PVCCINFAON_CPU0_VCC
  40  VCCS  POWER  = PVCCINFAON_CPU0_VREF
  TH  TH_GND  POWER  = GND
